(kicad_pcb
	(version 20260206)
	(generator "pcbnew")
	(generator_version "10.0")
	(general
		(thickness 1.6)
		(legacy_teardrops no)
	)
	(paper "A4")
	(title_block
		(title "03242023_DA0F0TMBIJ0_F0T_Motherboard_J_brd_V01_OCP.brd")
		(comment 1 "Grand Teton / footprints 3990-3996 of 6105")
	)
	(layers
		(0 "F.Cu" signal "TOP")
		(4 "In1.Cu" signal "GND")
		(6 "In2.Cu" signal "IN1")
		(8 "In3.Cu" signal "GND1")
		(10 "In4.Cu" signal "IN2")
		(12 "In5.Cu" signal "GND2")
		(14 "In6.Cu" signal "IN3")
		(16 "In7.Cu" signal "GND3")
		(18 "In8.Cu" signal "VCC")
		(20 "In9.Cu" signal "VCC1")
		(22 "In10.Cu" signal "GND4")
		(24 "In11.Cu" signal "IN4")
		(26 "In12.Cu" signal "GND5")
		(28 "In13.Cu" signal "IN5")
		(30 "In14.Cu" signal "GND6")
		(32 "In15.Cu" signal "IN6")
		(34 "In16.Cu" signal "GND7")
		(2 "B.Cu" signal "BOTTOM")
		(9 "F.Adhes" user "F.Adhesive")
		(11 "B.Adhes" user "B.Adhesive")
		(13 "F.Paste" user "Package Geometry/Pastemask Top")
		(15 "B.Paste" user "Package Geometry/Pastemask Bottom")
		(5 "F.SilkS" user "Ref Des/Silkscreen Top")
		(7 "B.SilkS" user "Ref Des/Silkscreen Bottom")
		(1 "F.Mask" user "Board Geometry/Soldermask Top")
		(3 "B.Mask" user "Board Geometry/Soldermask Bottom")
		(17 "Dwgs.User" user "User.Drawings")
		(19 "Cmts.User" user "User.Comments")
		(21 "Eco1.User" user "User.Eco1")
		(23 "Eco2.User" user "User.Eco2")
		(25 "Edge.Cuts" user "Board Geometry/Outline")
		(27 "Margin" user)
		(31 "F.CrtYd" user "Package Geometry/Place Bound Top")
		(29 "B.CrtYd" user "Package Geometry/Place Bound Bottom")
		(35 "F.Fab" user "Ref Des/Assembly Top")
		(33 "B.Fab" user "Ref Des/Assembly Bottom")
	)
	(footprint ""
		(layer "F.Cu")
		(at 320.190622 -57.267348)
		(property "Reference" "R619"
			(at 0 0 0)
			(layer "F.SilkS")
			(hide yes)
			(effects
				(font
					(size 1.27 1.27)
				)
			)
		)
		(property "Value" ""
			(at 0 0 0)
			(layer "F.Fab")
			(effects
				(font
					(size 1.27 1.27)
				)
			)
		)
		(duplicate_pad_numbers_are_jumpers no)
		(fp_line
			(start -0.7874 -0.4064)
			(end 0.7874 -0.4064)
			(stroke
				(width 0.1524)
				(type default)
			)
			(layer "F.SilkS")
		)
		(fp_line
			(start -0.7874 0.4064)
			(end -0.7874 -0.4064)
			(stroke
				(width 0.1524)
				(type default)
			)
			(layer "F.SilkS")
		)
		(fp_line
			(start 0.7874 -0.4064)
			(end 0.7874 0.4064)
			(stroke
				(width 0.1524)
				(type default)
			)
			(layer "F.SilkS")
		)
		(fp_line
			(start 0.7874 0.4064)
			(end -0.7874 0.4064)
			(stroke
				(width 0.1524)
				(type default)
			)
			(layer "F.SilkS")
		)
		(fp_line
			(start -0.67945 -0.305054)
			(end -0.12065 -0.305054)
			(stroke
				(width 0.1)
				(type default)
			)
			(layer "F.Fab")
		)
		(fp_line
			(start -0.67945 0.3048)
			(end -0.67945 -0.305054)
			(stroke
				(width 0.1)
				(type default)
			)
			(layer "F.Fab")
		)
		(fp_line
			(start -0.12065 -0.305054)
			(end -0.12065 -0.2794)
			(stroke
				(width 0.1)
				(type default)
			)
			(layer "F.Fab")
		)
		(fp_line
			(start -0.12065 -0.2794)
			(end 0.12065 -0.2794)
			(stroke
				(width 0.1)
				(type default)
			)
			(layer "F.Fab")
		)
		(fp_line
			(start -0.12065 0.2794)
			(end -0.12065 0.3048)
			(stroke
				(width 0.1)
				(type default)
			)
			(layer "F.Fab")
		)
		(fp_line
			(start -0.12065 0.3048)
			(end -0.67945 0.3048)
			(stroke
				(width 0.1)
				(type default)
			)
			(layer "F.Fab")
		)
		(fp_line
			(start 0.120396 0.2794)
			(end -0.12065 0.2794)
			(stroke
				(width 0.1)
				(type default)
			)
			(layer "F.Fab")
		)
		(fp_line
			(start 0.120396 0.3048)
			(end 0.120396 0.2794)
			(stroke
				(width 0.1)
				(type default)
			)
			(layer "F.Fab")
		)
		(fp_line
			(start 0.12065 -0.3048)
			(end 0.67945 -0.3048)
			(stroke
				(width 0.1)
				(type default)
			)
			(layer "F.Fab")
		)
		(fp_line
			(start 0.12065 -0.2794)
			(end 0.12065 -0.3048)
			(stroke
				(width 0.1)
				(type default)
			)
			(layer "F.Fab")
		)
		(fp_line
			(start 0.67945 -0.3048)
			(end 0.67945 0.3048)
			(stroke
				(width 0.1)
				(type default)
			)
			(layer "F.Fab")
		)
		(fp_line
			(start 0.67945 0.3048)
			(end 0.120396 0.3048)
			(stroke
				(width 0.1)
				(type default)
			)
			(layer "F.Fab")
		)
		(pad "1" smd circle
			(at -0.40005 0)
			(size 0 0)
			(layers "F.Cu" "F.Mask" "F.Paste")
			(net "P3V3_AUX")
		)
		(pad "2" smd circle
			(at 0.40005 0)
			(size 0 0)
			(layers "F.Cu" "F.Mask" "F.Paste")
			(net "FM_LT_KEY_DOWNGRADE_N")
		)
	)
	(footprint ""
		(layer "F.Cu")
		(at 68.147438 -32.776922 90)
		(property "Reference" "PR3847"
			(at 0 0 90)
			(layer "F.SilkS")
			(hide yes)
			(effects
				(font
					(size 1.27 1.27)
				)
			)
		)
		(property "Value" ""
			(at 0 0 90)
			(layer "F.Fab")
			(effects
				(font
					(size 1.27 1.27)
				)
			)
		)
		(duplicate_pad_numbers_are_jumpers no)
		(fp_line
			(start 0.7874 -0.4064)
			(end 0.7874 0.4064)
			(stroke
				(width 0.1524)
				(type default)
			)
			(layer "F.SilkS")
		)
		(fp_line
			(start -0.7874 -0.4064)
			(end 0.7874 -0.4064)
			(stroke
				(width 0.1524)
				(type default)
			)
			(layer "F.SilkS")
		)
		(fp_line
			(start 0.7874 0.4064)
			(end -0.7874 0.4064)
			(stroke
				(width 0.1524)
				(type default)
			)
			(layer "F.SilkS")
		)
		(fp_line
			(start -0.7874 0.4064)
			(end -0.7874 -0.4064)
			(stroke
				(width 0.1524)
				(type default)
			)
			(layer "F.SilkS")
		)
		(fp_line
			(start -0.12065 -0.305054)
			(end -0.12065 -0.2794)
			(stroke
				(width 0.1)
				(type default)
			)
			(layer "F.Fab")
		)
		(fp_line
			(start -0.67945 -0.305054)
			(end -0.12065 -0.305054)
			(stroke
				(width 0.1)
				(type default)
			)
			(layer "F.Fab")
		)
		(fp_line
			(start 0.67945 -0.3048)
			(end 0.67945 0.3048)
			(stroke
				(width 0.1)
				(type default)
			)
			(layer "F.Fab")
		)
		(fp_line
			(start 0.12065 -0.3048)
			(end 0.67945 -0.3048)
			(stroke
				(width 0.1)
				(type default)
			)
			(layer "F.Fab")
		)
		(fp_line
			(start 0.12065 -0.2794)
			(end 0.12065 -0.3048)
			(stroke
				(width 0.1)
				(type default)
			)
			(layer "F.Fab")
		)
		(fp_line
			(start -0.12065 -0.2794)
			(end 0.12065 -0.2794)
			(stroke
				(width 0.1)
				(type default)
			)
			(layer "F.Fab")
		)
		(fp_line
			(start 0.120396 0.2794)
			(end -0.12065 0.2794)
			(stroke
				(width 0.1)
				(type default)
			)
			(layer "F.Fab")
		)
		(fp_line
			(start -0.12065 0.2794)
			(end -0.12065 0.3048)
			(stroke
				(width 0.1)
				(type default)
			)
			(layer "F.Fab")
		)
		(fp_line
			(start 0.67945 0.3048)
			(end 0.120396 0.3048)
			(stroke
				(width 0.1)
				(type default)
			)
			(layer "F.Fab")
		)
		(fp_line
			(start 0.120396 0.3048)
			(end 0.120396 0.2794)
			(stroke
				(width 0.1)
				(type default)
			)
			(layer "F.Fab")
		)
		(fp_line
			(start -0.12065 0.3048)
			(end -0.67945 0.3048)
			(stroke
				(width 0.1)
				(type default)
			)
			(layer "F.Fab")
		)
		(fp_line
			(start -0.67945 0.3048)
			(end -0.67945 -0.305054)
			(stroke
				(width 0.1)
				(type default)
			)
			(layer "F.Fab")
		)
		(pad "1" smd circle
			(at -0.40005 0 90)
			(size 0 0)
			(layers "F.Cu" "F.Mask" "F.Paste")
			(net "P12V_OCP_ISET_2")
		)
		(pad "2" smd circle
			(at 0.40005 0 90)
			(size 0 0)
			(layers "F.Cu" "F.Mask" "F.Paste")
			(net "GND")
		)
	)
	(footprint ""
		(layer "F.Cu")
		(at 70.228714 -65.082674 -90)
		(property "Reference" "R3084"
			(at 0 0 270)
			(layer "F.SilkS")
			(hide yes)
			(effects
				(font
					(size 1.27 1.27)
				)
			)
		)
		(property "Value" ""
			(at 0 0 270)
			(layer "F.Fab")
			(effects
				(font
					(size 1.27 1.27)
				)
			)
		)
		(duplicate_pad_numbers_are_jumpers no)
		(fp_line
			(start -0.7874 0.4064)
			(end -0.7874 -0.4064)
			(stroke
				(width 0.1524)
				(type default)
			)
			(layer "F.SilkS")
		)
		(fp_line
			(start 0.7874 0.4064)
			(end -0.7874 0.4064)
			(stroke
				(width 0.1524)
				(type default)
			)
			(layer "F.SilkS")
		)
		(fp_line
			(start -0.7874 -0.4064)
			(end 0.7874 -0.4064)
			(stroke
				(width 0.1524)
				(type default)
			)
			(layer "F.SilkS")
		)
		(fp_line
			(start 0.7874 -0.4064)
			(end 0.7874 0.4064)
			(stroke
				(width 0.1524)
				(type default)
			)
			(layer "F.SilkS")
		)
		(fp_line
			(start -0.67945 0.3048)
			(end -0.67945 -0.305054)
			(stroke
				(width 0.1)
				(type default)
			)
			(layer "F.Fab")
		)
		(fp_line
			(start -0.12065 0.3048)
			(end -0.67945 0.3048)
			(stroke
				(width 0.1)
				(type default)
			)
			(layer "F.Fab")
		)
		(fp_line
			(start 0.120396 0.3048)
			(end 0.120396 0.2794)
			(stroke
				(width 0.1)
				(type default)
			)
			(layer "F.Fab")
		)
		(fp_line
			(start 0.67945 0.3048)
			(end 0.120396 0.3048)
			(stroke
				(width 0.1)
				(type default)
			)
			(layer "F.Fab")
		)
		(fp_line
			(start -0.12065 0.2794)
			(end -0.12065 0.3048)
			(stroke
				(width 0.1)
				(type default)
			)
			(layer "F.Fab")
		)
		(fp_line
			(start 0.120396 0.2794)
			(end -0.12065 0.2794)
			(stroke
				(width 0.1)
				(type default)
			)
			(layer "F.Fab")
		)
		(fp_line
			(start -0.12065 -0.2794)
			(end 0.12065 -0.2794)
			(stroke
				(width 0.1)
				(type default)
			)
			(layer "F.Fab")
		)
		(fp_line
			(start 0.12065 -0.2794)
			(end 0.12065 -0.3048)
			(stroke
				(width 0.1)
				(type default)
			)
			(layer "F.Fab")
		)
		(fp_line
			(start 0.12065 -0.3048)
			(end 0.67945 -0.3048)
			(stroke
				(width 0.1)
				(type default)
			)
			(layer "F.Fab")
		)
		(fp_line
			(start 0.67945 -0.3048)
			(end 0.67945 0.3048)
			(stroke
				(width 0.1)
				(type default)
			)
			(layer "F.Fab")
		)
		(fp_line
			(start -0.67945 -0.305054)
			(end -0.12065 -0.305054)
			(stroke
				(width 0.1)
				(type default)
			)
			(layer "F.Fab")
		)
		(fp_line
			(start -0.12065 -0.305054)
			(end -0.12065 -0.2794)
			(stroke
				(width 0.1)
				(type default)
			)
			(layer "F.Fab")
		)
		(pad "1" smd circle
			(at -0.40005 0 270)
			(size 0 0)
			(layers "F.Cu" "F.Mask" "F.Paste")
			(net "LED_RST_PLD_CPU1_DRAM_CD_N")
		)
		(pad "2" smd circle
			(at 0.40005 0 270)
			(size 0 0)
			(layers "F.Cu" "F.Mask" "F.Paste")
			(net "P3V3_AUX")
		)
	)
	(footprint ""
		(layer "F.Cu")
		(at 47.462694 -17.623536 90)
		(property "Reference" "C829"
			(at 0 0 90)
			(layer "F.SilkS")
			(hide yes)
			(effects
				(font
					(size 1.27 1.27)
				)
			)
		)
		(property "Value" ""
			(at 0 0 90)
			(layer "F.Fab")
			(effects
				(font
					(size 1.27 1.27)
				)
			)
		)
		(duplicate_pad_numbers_are_jumpers no)
		(fp_line
			(start 0.299974 -0.150114)
			(end 0.299974 0.150114)
			(stroke
				(width 0.1)
				(type default)
			)
			(layer "F.Fab")
		)
		(fp_line
			(start -0.299974 -0.150114)
			(end 0.299974 -0.150114)
			(stroke
				(width 0.1)
				(type default)
			)
			(layer "F.Fab")
		)
		(fp_line
			(start 0.299974 0.150114)
			(end -0.299974 0.150114)
			(stroke
				(width 0.1)
				(type default)
			)
			(layer "F.Fab")
		)
		(fp_line
			(start -0.299974 0.150114)
			(end -0.299974 -0.150114)
			(stroke
				(width 0.1)
				(type default)
			)
			(layer "F.Fab")
		)
		(pad "1" smd rect
			(at -0.2667 0 90)
			(size 0.3048 0.381)
			(layers "F.Cu" "F.Mask" "F.Paste")
			(net "P5E_CPU1_PE1_TX_C_DP<4>")
		)
		(pad "2" smd rect
			(at 0.2667 0 90)
			(size 0.3048 0.381)
			(layers "F.Cu" "F.Mask" "F.Paste")
			(net "P5E_CPU1_PE1_TX_DP<4>")
		)
	)
	(footprint ""
		(layer "F.Cu")
		(at 88.925146 -206.024734)
		(property "Reference" "H20"
			(at -0.34036 3.860292 0)
			(unlocked yes)
			(layer "F.SilkS")
			(effects
				(font
					(size 0.7874 0.5842)
					(thickness 0.1524)
				)
				(justify left)
			)
		)
		(property "Value" ""
			(at 0 0 0)
			(layer "F.Fab")
			(effects
				(font
					(size 1.27 1.27)
				)
			)
		)
		(duplicate_pad_numbers_are_jumpers no)
		(fp_circle
			(center 0 0)
			(end 2.5273 0)
			(stroke
				(width 0.1524)
				(type default)
			)
			(fill no)
			(layer "F.SilkS")
		)
		(fp_circle
			(center 0 0)
			(end 2.5273 0)
			(stroke
				(width 0.1524)
				(type default)
			)
			(fill no)
			(layer "B.SilkS")
		)
		(fp_circle
			(center 0 0)
			(end 2.5273 0)
			(stroke
				(width 0.1)
				(type default)
			)
			(fill no)
			(layer "B.Fab")
		)
		(fp_circle
			(center 0 0)
			(end 2.5273 0)
			(stroke
				(width 0.1)
				(type default)
			)
			(fill no)
			(layer "F.Fab")
		)
		(pad "" np_thru_hole circle
			(at 0 0)
			(size 3.429 3.429)
			(drill 3.429)
			(layers "*.Cu" "*.Mask")
			(clearance 0.381)
			(thermal_gap 0.381)
		)
	)
	(footprint ""
		(layer "F.Cu")
		(at 379.443996 -92.887292 -90)
		(property "Reference" "R1382"
			(at 0 0 270)
			(layer "F.SilkS")
			(hide yes)
			(effects
				(font
					(size 1.27 1.27)
				)
			)
		)
		(property "Value" ""
			(at 0 0 270)
			(layer "F.Fab")
			(effects
				(font
					(size 1.27 1.27)
				)
			)
		)
		(duplicate_pad_numbers_are_jumpers no)
		(fp_line
			(start -0.7874 0.4064)
			(end -0.7874 -0.4064)
			(stroke
				(width 0.1524)
				(type default)
			)
			(layer "F.SilkS")
		)
		(fp_line
			(start 0.7874 0.4064)
			(end -0.7874 0.4064)
			(stroke
				(width 0.1524)
				(type default)
			)
			(layer "F.SilkS")
		)
		(fp_line
			(start -0.7874 -0.4064)
			(end 0.7874 -0.4064)
			(stroke
				(width 0.1524)
				(type default)
			)
			(layer "F.SilkS")
		)
		(fp_line
			(start 0.7874 -0.4064)
			(end 0.7874 0.4064)
			(stroke
				(width 0.1524)
				(type default)
			)
			(layer "F.SilkS")
		)
		(fp_line
			(start -0.67945 0.3048)
			(end -0.67945 -0.305054)
			(stroke
				(width 0.1)
				(type default)
			)
			(layer "F.Fab")
		)
		(fp_line
			(start -0.12065 0.3048)
			(end -0.67945 0.3048)
			(stroke
				(width 0.1)
				(type default)
			)
			(layer "F.Fab")
		)
		(fp_line
			(start 0.120396 0.3048)
			(end 0.120396 0.2794)
			(stroke
				(width 0.1)
				(type default)
			)
			(layer "F.Fab")
		)
		(fp_line
			(start 0.67945 0.3048)
			(end 0.120396 0.3048)
			(stroke
				(width 0.1)
				(type default)
			)
			(layer "F.Fab")
		)
		(fp_line
			(start -0.12065 0.2794)
			(end -0.12065 0.3048)
			(stroke
				(width 0.1)
				(type default)
			)
			(layer "F.Fab")
		)
		(fp_line
			(start 0.120396 0.2794)
			(end -0.12065 0.2794)
			(stroke
				(width 0.1)
				(type default)
			)
			(layer "F.Fab")
		)
		(fp_line
			(start -0.12065 -0.2794)
			(end 0.12065 -0.2794)
			(stroke
				(width 0.1)
				(type default)
			)
			(layer "F.Fab")
		)
		(fp_line
			(start 0.12065 -0.2794)
			(end 0.12065 -0.3048)
			(stroke
				(width 0.1)
				(type default)
			)
			(layer "F.Fab")
		)
		(fp_line
			(start 0.12065 -0.3048)
			(end 0.67945 -0.3048)
			(stroke
				(width 0.1)
				(type default)
			)
			(layer "F.Fab")
		)
		(fp_line
			(start 0.67945 -0.3048)
			(end 0.67945 0.3048)
			(stroke
				(width 0.1)
				(type default)
			)
			(layer "F.Fab")
		)
		(fp_line
			(start -0.67945 -0.305054)
			(end -0.12065 -0.305054)
			(stroke
				(width 0.1)
				(type default)
			)
			(layer "F.Fab")
		)
		(fp_line
			(start -0.12065 -0.305054)
			(end -0.12065 -0.2794)
			(stroke
				(width 0.1)
				(type default)
			)
			(layer "F.Fab")
		)
		(pad "1" smd circle
			(at -0.40005 0 270)
			(size 0 0)
			(layers "F.Cu" "F.Mask" "F.Paste")
			(net "P3V3_AUX")
		)
		(pad "2" smd circle
			(at 0.40005 0 270)
			(size 0 0)
			(layers "F.Cu" "F.Mask" "F.Paste")
			(net "JTAG_DBP_BMC_PRDY_N")
		)
	)
	(footprint ""
		(layer "F.Cu")
		(at 354.282248 -249.320304 -90)
		(property "Reference" "C1038"
			(at 0 0 270)
			(layer "F.SilkS")
			(hide yes)
			(effects
				(font
					(size 1.27 1.27)
				)
			)
		)
		(property "Value" ""
			(at 0 0 270)
			(layer "F.Fab")
			(effects
				(font
					(size 1.27 1.27)
				)
			)
		)
		(duplicate_pad_numbers_are_jumpers no)
		(fp_line
			(start -0.7874 0.4064)
			(end -0.7874 -0.4064)
			(stroke
				(width 0.1524)
				(type default)
			)
			(layer "F.SilkS")
		)
		(fp_line
			(start 0.7874 0.4064)
			(end -0.7874 0.4064)
			(stroke
				(width 0.1524)
				(type default)
			)
			(layer "F.SilkS")
		)
		(fp_line
			(start -0.7874 -0.4064)
			(end 0.7874 -0.4064)
			(stroke
				(width 0.1524)
				(type default)
			)
			(layer "F.SilkS")
		)
		(fp_line
			(start 0.7874 -0.4064)
			(end 0.7874 0.4064)
			(stroke
				(width 0.1524)
				(type default)
			)
			(layer "F.SilkS")
		)
		(fp_line
			(start -0.67945 0.3048)
			(end -0.67945 -0.305054)
			(stroke
				(width 0.1)
				(type default)
			)
			(layer "F.Fab")
		)
		(fp_line
			(start -0.12065 0.3048)
			(end -0.67945 0.3048)
			(stroke
				(width 0.1)
				(type default)
			)
			(layer "F.Fab")
		)
		(fp_line
			(start 0.120396 0.3048)
			(end 0.120396 0.2794)
			(stroke
				(width 0.1)
				(type default)
			)
			(layer "F.Fab")
		)
		(fp_line
			(start 0.67945 0.3048)
			(end 0.120396 0.3048)
			(stroke
				(width 0.1)
				(type default)
			)
			(layer "F.Fab")
		)
		(fp_line
			(start -0.12065 0.2794)
			(end -0.12065 0.3048)
			(stroke
				(width 0.1)
				(type default)
			)
			(layer "F.Fab")
		)
		(fp_line
			(start 0.120396 0.2794)
			(end -0.12065 0.2794)
			(stroke
				(width 0.1)
				(type default)
			)
			(layer "F.Fab")
		)
		(fp_line
			(start -0.12065 -0.2794)
			(end 0.12065 -0.2794)
			(stroke
				(width 0.1)
				(type default)
			)
			(layer "F.Fab")
		)
		(fp_line
			(start 0.12065 -0.2794)
			(end 0.12065 -0.3048)
			(stroke
				(width 0.1)
				(type default)
			)
			(layer "F.Fab")
		)
		(fp_line
			(start 0.12065 -0.3048)
			(end 0.67945 -0.3048)
			(stroke
				(width 0.1)
				(type default)
			)
			(layer "F.Fab")
		)
		(fp_line
			(start 0.67945 -0.3048)
			(end 0.67945 0.3048)
			(stroke
				(width 0.1)
				(type default)
			)
			(layer "F.Fab")
		)
		(fp_line
			(start -0.67945 -0.305054)
			(end -0.12065 -0.305054)
			(stroke
				(width 0.1)
				(type default)
			)
			(layer "F.Fab")
		)
		(fp_line
			(start -0.12065 -0.305054)
			(end -0.12065 -0.2794)
			(stroke
				(width 0.1)
				(type default)
			)
			(layer "F.Fab")
		)
		(pad "1" smd circle
			(at -0.40005 0 270)
			(size 0 0)
			(layers "F.Cu" "F.Mask" "F.Paste")
			(net "PVCCIN_CPU0")
		)
		(pad "2" smd circle
			(at 0.40005 0 270)
			(size 0 0)
			(layers "F.Cu" "F.Mask" "F.Paste")
			(net "GND")
		)
	)
)
